(kicad_pcb
	(version 20260206)
	(generator "pcbnew")
	(generator_version "10.0")
	(general
		(thickness 1.6)
		(legacy_teardrops no)
	)
	(paper "A4")
	(title_block
		(title "Wiwynn_Tioga_Pass_MB.brd")
		(comment 1 "Tioga Pass / footprint 190 of 4770 (U2D1), pads 2074-2186 of 3647")
	)
	(layers
		(0 "F.Cu" signal "TOP")
		(4 "In1.Cu" signal "L2GND")
		(6 "In2.Cu" signal "L3")
		(8 "In3.Cu" signal "L4GND")
		(10 "In4.Cu" signal "L5")
		(12 "In5.Cu" signal "L6GND")
		(14 "In6.Cu" signal "L7VCC")
		(16 "In7.Cu" signal "L8VCC")
		(18 "In8.Cu" signal "L9GND")
		(20 "In9.Cu" signal "L10")
		(22 "In10.Cu" signal "L11GND")
		(24 "In11.Cu" signal "L12")
		(26 "In12.Cu" signal "L13GND")
		(2 "B.Cu" signal "BOTTOM")
		(9 "F.Adhes" user "F.Adhesive")
		(11 "B.Adhes" user "B.Adhesive")
		(13 "F.Paste" user "Package Geometry/Pastemask Top")
		(15 "B.Paste" user "Package Geometry/Pastemask Bottom")
		(5 "F.SilkS" user "Ref Des/Silkscreen Top")
		(7 "B.SilkS" user "Ref Des/Silkscreen Bottom")
		(1 "F.Mask" user "Board Geometry/Soldermask Top")
		(3 "B.Mask" user "Board Geometry/Soldermask Bottom")
		(17 "Dwgs.User" user "User.Drawings")
		(19 "Cmts.User" user "User.Comments")
		(21 "Eco1.User" user "User.Eco1")
		(23 "Eco2.User" user "User.Eco2")
		(25 "Edge.Cuts" user "Board Geometry/Outline")
		(27 "Margin" user)
		(31 "F.CrtYd" user "Package Geometry/Place Bound Top")
		(29 "B.CrtYd" user "Package Geometry/Place Bound Bottom")
		(35 "F.Fab" user "Ref Des/Assembly Top")
		(33 "B.Fab" user "Ref Des/Assembly Bottom")
	)
	(footprint ""
		(layer "F.Cu")
		(at 104.99979 -76.550012 180)
		(property "Reference" "U2D1"
			(at 25.19299 30.484318 0)
			(unlocked yes)
			(layer "F.SilkS")
			(effects
				(font
					(size 0.7874 0.5842)
					(thickness 0.1524)
				)
			)
		)
		(property "Value" ""
			(at 0 0 180)
			(layer "F.Fab")
			(effects
				(font
					(size 1.27 1.27)
				)
			)
		)
		(duplicate_pad_numbers_are_jumpers no)
		(pad "DD13" smd circle
			(at -26.948384 16.006572)
			(size 0.4318 0.4318)
			(layers "F.Cu" "F.Mask" "F.Paste")
			(net "P3E_CPU1_PE3_MP_RXP<12>")
		)
		(pad "DD15" smd circle
			(at -25.231598 16.006572)
			(size 0.4318 0.4318)
			(layers "F.Cu" "F.Mask" "F.Paste")
			(net "TP_CPU1_UPI2_RSVD_CV13")
		)
		(pad "DD17" smd circle
			(at -23.514558 16.006572)
			(size 0.4318 0.4318)
			(layers "F.Cu" "F.Mask" "F.Paste")
			(net "TP_CPU1_UPI2_RSVD_CU14")
		)
		(pad "DD19" smd circle
			(at -21.797518 16.006572)
			(size 0.4318 0.4318)
			(layers "F.Cu" "F.Mask" "F.Paste")
			(net "GND")
		)
		(pad "DD21" smd circle
			(at -20.080478 16.006572)
			(size 0.4318 0.4318)
			(layers "F.Cu" "F.Mask" "F.Paste")
			(net "GND")
		)
		(pad "DD23" smd circle
			(at -18.363438 16.006572)
			(size 0.4318 0.4318)
			(layers "F.Cu" "F.Mask" "F.Paste")
			(net "GND")
		)
		(pad "DD25" smd circle
			(at -16.646398 16.006572)
			(size 0.4318 0.4318)
			(layers "F.Cu" "F.Mask" "F.Paste")
			(net "M_L_DQ<58>")
		)
		(pad "DD27" smd circle
			(at -14.929612 16.006572)
			(size 0.4318 0.4318)
			(layers "F.Cu" "F.Mask" "F.Paste")
			(net "GND")
		)
		(pad "DD29" smd circle
			(at -13.212572 16.006572)
			(size 0.4318 0.4318)
			(layers "F.Cu" "F.Mask" "F.Paste")
			(net "M_M_DQS_DN<7>")
		)
		(pad "DD31" smd circle
			(at -11.495532 16.006572)
			(size 0.4318 0.4318)
			(layers "F.Cu" "F.Mask" "F.Paste")
			(net "GND")
		)
		(pad "DD33" smd circle
			(at -9.778492 16.006572)
			(size 0.4318 0.4318)
			(layers "F.Cu" "F.Mask" "F.Paste")
			(net "GND")
		)
		(pad "DD35" smd circle
			(at -8.061452 16.006572)
			(size 0.4318 0.4318)
			(layers "F.Cu" "F.Mask" "F.Paste")
			(net "M_M_DQS_DN<6>")
		)
		(pad "DD37" smd circle
			(at -6.344412 16.006572)
			(size 0.4318 0.4318)
			(layers "F.Cu" "F.Mask" "F.Paste")
			(net "GND")
		)
		(pad "DD39" smd circle
			(at -4.627626 16.006572)
			(size 0.4318 0.4318)
			(layers "F.Cu" "F.Mask" "F.Paste")
			(net "M_M_DQ<38>")
		)
		(pad "DD41" smd circle
			(at -2.910586 16.006572)
			(size 0.4318 0.4318)
			(layers "F.Cu" "F.Mask" "F.Paste")
			(net "M_M_DQ<32>")
		)
		(pad "DD45" smd circle
			(at 2.052066 14.206474)
			(size 0.4318 0.4318)
			(layers "F.Cu" "F.Mask" "F.Paste")
			(net "PVDDQ_KLM")
		)
		(pad "DD47" smd circle
			(at 3.769106 14.206474)
			(size 0.4318 0.4318)
			(layers "F.Cu" "F.Mask" "F.Paste")
			(net "A_CPU1_KLM_RCOMP1")
		)
		(pad "DD49" smd circle
			(at 5.485892 14.206474)
			(size 0.4318 0.4318)
			(layers "F.Cu" "F.Mask" "F.Paste")
			(net "A_CPU1_KLM_RCOMP2")
		)
		(pad "DD51" smd circle
			(at 7.202932 14.206474)
			(size 0.4318 0.4318)
			(layers "F.Cu" "F.Mask" "F.Paste")
			(net "TP_CPU1_RSVD_45")
		)
		(pad "DD53" smd circle
			(at 8.919972 14.206474)
			(size 0.4318 0.4318)
			(layers "F.Cu" "F.Mask" "F.Paste")
			(net "M_M_MA<13>")
		)
		(pad "DD55" smd circle
			(at 10.637012 14.206474)
			(size 0.4318 0.4318)
			(layers "F.Cu" "F.Mask" "F.Paste")
			(net "M_M_MA<10>")
		)
		(pad "DD57" smd circle
			(at 12.354052 14.206474)
			(size 0.4318 0.4318)
			(layers "F.Cu" "F.Mask" "F.Paste")
			(net "M_M_MA<2>")
		)
		(pad "DD59" smd circle
			(at 14.071092 14.206474)
			(size 0.4318 0.4318)
			(layers "F.Cu" "F.Mask" "F.Paste")
			(net "M_M_MA<8>")
		)
		(pad "DD61" smd circle
			(at 15.787878 14.206474)
			(size 0.4318 0.4318)
			(layers "F.Cu" "F.Mask" "F.Paste")
			(net "M_M_ALERT_N")
		)
		(pad "DD63" smd circle
			(at 17.504918 14.206474)
			(size 0.4318 0.4318)
			(layers "F.Cu" "F.Mask" "F.Paste")
			(net "M_M_CKE<1>")
		)
		(pad "DD65" smd circle
			(at 19.221958 14.206474)
			(size 0.4318 0.4318)
			(layers "F.Cu" "F.Mask" "F.Paste")
			(net "M_K_ECC<3>")
		)
		(pad "DD67" smd circle
			(at 20.938998 14.206474)
			(size 0.4318 0.4318)
			(layers "F.Cu" "F.Mask" "F.Paste")
			(net "M_K_DQS_DP<8>")
		)
		(pad "DD69" smd circle
			(at 22.656038 14.206474)
			(size 0.4318 0.4318)
			(layers "F.Cu" "F.Mask" "F.Paste")
			(net "M_K_ECC<5>")
		)
		(pad "DD71" smd circle
			(at 24.373078 14.206474)
			(size 0.4318 0.4318)
			(layers "F.Cu" "F.Mask" "F.Paste")
			(net "GND")
		)
		(pad "DD73" smd circle
			(at 26.090118 14.206474)
			(size 0.4318 0.4318)
			(layers "F.Cu" "F.Mask" "F.Paste")
			(net "GND")
		)
		(pad "DD75" smd circle
			(at 27.806904 14.206474)
			(size 0.4318 0.4318)
			(layers "F.Cu" "F.Mask" "F.Paste")
			(net "GND")
		)
		(pad "DD77" smd circle
			(at 29.523944 14.206474)
			(size 0.4318 0.4318)
			(layers "F.Cu" "F.Mask" "F.Paste")
			(net "M_M_DQS_DN<1>")
		)
		(pad "DD79" smd circle
			(at 31.240984 14.206474)
			(size 0.4318 0.4318)
			(layers "F.Cu" "F.Mask" "F.Paste")
			(net "M_L_DQS_DP<10>")
		)
		(pad "DD81" smd circle
			(at 32.958024 14.206474)
			(size 0.4318 0.4318)
			(layers "F.Cu" "F.Mask" "F.Paste")
			(net "GND")
		)
		(pad "DD83" smd circle
			(at 34.675064 14.206474)
			(size 0.4318 0.4318)
			(layers "F.Cu" "F.Mask" "F.Paste")
			(net "GND")
		)
		(pad "DD85" smd custom
			(at 36.392104 14.206474 270)
			(size 0.10795 0.10795)
			(layers "F.Cu" "F.Mask" "F.Paste")
			(net "M_K_DQ<12>")
			(options
				(clearance outline)
				(anchor circle)
			)
			(primitives
				(gr_poly
					(pts
						(arc
							(start 0.2159 -0.0381)
							(mid 0 -0.254)
							(end -0.2159 -0.0381)
						)
						(arc
							(start -0.2159 0.0381)
							(mid 0 0.254)
							(end 0.2159 0.0381)
						)
					)
					(width 0)
					(fill yes)
				)
			)
		)
		(pad "DE2" smd custom
			(at -36.392104 16.502126 90)
			(size 0.10795 0.10795)
			(layers "F.Cu" "F.Mask" "F.Paste")
			(net "TP_P3E_CPU1_PE1_MP_TXN<2>")
			(options
				(clearance outline)
				(anchor circle)
			)
			(primitives
				(gr_poly
					(pts
						(arc
							(start 0.2159 -0.0381)
							(mid 0 -0.254)
							(end -0.2159 -0.0381)
						)
						(arc
							(start -0.2159 0.0381)
							(mid 0 0.254)
							(end 0.2159 0.0381)
						)
					)
					(width 0)
					(fill yes)
				)
			)
		)
		(pad "DE4" smd circle
			(at -34.675064 16.502126)
			(size 0.4318 0.4318)
			(layers "F.Cu" "F.Mask" "F.Paste")
			(net "TP_P3E_CPU1_PE1_MP_TXN<3>")
		)
		(pad "DE6" smd circle
			(at -32.958024 16.502126)
			(size 0.4318 0.4318)
			(layers "F.Cu" "F.Mask" "F.Paste")
			(net "GND")
		)
		(pad "DE8" smd circle
			(at -31.240984 16.502126)
			(size 0.4318 0.4318)
			(layers "F.Cu" "F.Mask" "F.Paste")
			(net "GND")
		)
		(pad "DE10" smd circle
			(at -29.523944 16.502126)
			(size 0.4318 0.4318)
			(layers "F.Cu" "F.Mask" "F.Paste")
			(net "TP_P3E_CPU1_PE1_MP_RXN<4>")
		)
		(pad "DE12" smd circle
			(at -27.806904 16.502126)
			(size 0.4318 0.4318)
			(layers "F.Cu" "F.Mask" "F.Paste")
			(net "P3E_CPU1_PE3_MP_RXP<10>")
		)
		(pad "DE14" smd circle
			(at -26.090118 16.502126)
			(size 0.4318 0.4318)
			(layers "F.Cu" "F.Mask" "F.Paste")
			(net "PVCCIO_CPU1")
		)
		(pad "DE16" smd circle
			(at -24.373078 16.502126)
			(size 0.4318 0.4318)
			(layers "F.Cu" "F.Mask" "F.Paste")
			(net "TP_CPU1_UPI2_RSVD_CR14")
		)
		(pad "DE18" smd circle
			(at -22.656038 16.502126)
			(size 0.4318 0.4318)
			(layers "F.Cu" "F.Mask" "F.Paste")
			(net "GND")
		)
		(pad "DE20" smd circle
			(at -20.938998 16.502126)
			(size 0.4318 0.4318)
			(layers "F.Cu" "F.Mask" "F.Paste")
			(net "GND")
		)
		(pad "DE22" smd circle
			(at -19.221958 16.502126)
			(size 0.4318 0.4318)
			(layers "F.Cu" "F.Mask" "F.Paste")
			(net "GND")
		)
		(pad "DE24" smd circle
			(at -17.504918 16.502126)
			(size 0.4318 0.4318)
			(layers "F.Cu" "F.Mask" "F.Paste")
			(net "GND")
		)
		(pad "DE26" smd circle
			(at -15.787878 16.502126)
			(size 0.4318 0.4318)
			(layers "F.Cu" "F.Mask" "F.Paste")
			(net "M_L_DQS_DP<16>")
		)
		(pad "DE28" smd circle
			(at -14.071092 16.502126)
			(size 0.4318 0.4318)
			(layers "F.Cu" "F.Mask" "F.Paste")
			(net "GND")
		)
		(pad "DE30" smd circle
			(at -12.354052 16.502126)
			(size 0.4318 0.4318)
			(layers "F.Cu" "F.Mask" "F.Paste")
			(net "GND")
		)
		(pad "DE32" smd circle
			(at -10.637012 16.502126)
			(size 0.4318 0.4318)
			(layers "F.Cu" "F.Mask" "F.Paste")
			(net "M_M_DQS_DP<14>")
		)
		(pad "DE34" smd circle
			(at -8.919972 16.502126)
			(size 0.4318 0.4318)
			(layers "F.Cu" "F.Mask" "F.Paste")
			(net "GND")
		)
		(pad "DE36" smd circle
			(at -7.202932 16.502126)
			(size 0.4318 0.4318)
			(layers "F.Cu" "F.Mask" "F.Paste")
			(net "GND")
		)
		(pad "DE38" smd circle
			(at -5.485892 16.502126)
			(size 0.4318 0.4318)
			(layers "F.Cu" "F.Mask" "F.Paste")
			(net "M_M_DQ<34>")
		)
		(pad "DE40" smd circle
			(at -3.769106 16.502126)
			(size 0.4318 0.4318)
			(layers "F.Cu" "F.Mask" "F.Paste")
			(net "M_M_DQS_DN<13>")
		)
		(pad "DE42" smd circle
			(at -2.052066 16.502126)
			(size 0.4318 0.4318)
			(layers "F.Cu" "F.Mask" "F.Paste")
			(net "M_M_DQ<37>")
		)
		(pad "DE44" smd circle
			(at 1.193546 14.702028)
			(size 0.508 0.508)
			(layers "F.Cu" "F.Mask" "F.Paste")
			(net "SVID_ALERT0_CPU1_N")
		)
		(pad "DE46" smd circle
			(at 2.910586 14.702028)
			(size 0.4318 0.4318)
			(layers "F.Cu" "F.Mask" "F.Paste")
			(net "M_M_MA<17>")
		)
		(pad "DE48" smd circle
			(at 4.627626 14.702028)
			(size 0.4318 0.4318)
			(layers "F.Cu" "F.Mask" "F.Paste")
			(net "GND")
		)
		(pad "DE50" smd circle
			(at 6.344412 14.702028)
			(size 0.4318 0.4318)
			(layers "F.Cu" "F.Mask" "F.Paste")
			(net "GND")
		)
		(pad "DE52" smd circle
			(at 8.061452 14.702028)
			(size 0.4318 0.4318)
			(layers "F.Cu" "F.Mask" "F.Paste")
			(net "GND")
		)
		(pad "DE54" smd circle
			(at 9.778492 14.702028)
			(size 0.4318 0.4318)
			(layers "F.Cu" "F.Mask" "F.Paste")
			(net "GND")
		)
		(pad "DE56" smd circle
			(at 11.495532 14.702028)
			(size 0.4318 0.4318)
			(layers "F.Cu" "F.Mask" "F.Paste")
			(net "GND")
		)
		(pad "DE58" smd circle
			(at 13.212572 14.702028)
			(size 0.4318 0.4318)
			(layers "F.Cu" "F.Mask" "F.Paste")
			(net "GND")
		)
		(pad "DE60" smd circle
			(at 14.929612 14.702028)
			(size 0.4318 0.4318)
			(layers "F.Cu" "F.Mask" "F.Paste")
			(net "GND")
		)
		(pad "DE62" smd circle
			(at 16.646398 14.702028)
			(size 0.4318 0.4318)
			(layers "F.Cu" "F.Mask" "F.Paste")
			(net "GND")
		)
		(pad "DE64" smd circle
			(at 18.363438 14.702028)
			(size 0.4318 0.4318)
			(layers "F.Cu" "F.Mask" "F.Paste")
			(net "GND")
		)
		(pad "DE66" smd circle
			(at 20.080478 14.702028)
			(size 0.4318 0.4318)
			(layers "F.Cu" "F.Mask" "F.Paste")
			(net "M_K_ECC<7>")
		)
		(pad "DE68" smd circle
			(at 21.797518 14.702028)
			(size 0.4318 0.4318)
			(layers "F.Cu" "F.Mask" "F.Paste")
			(net "M_K_ECC<1>")
		)
		(pad "DE70" smd circle
			(at 23.514558 14.702028)
			(size 0.4318 0.4318)
			(layers "F.Cu" "F.Mask" "F.Paste")
			(net "GND")
		)
		(pad "DE72" smd circle
			(at 25.231598 14.702028)
			(size 0.4318 0.4318)
			(layers "F.Cu" "F.Mask" "F.Paste")
			(net "GND")
		)
		(pad "DE74" smd circle
			(at 26.948384 14.702028)
			(size 0.4318 0.4318)
			(layers "F.Cu" "F.Mask" "F.Paste")
			(net "M_M_DQ<8>")
		)
		(pad "DE76" smd circle
			(at 28.665424 14.702028)
			(size 0.4318 0.4318)
			(layers "F.Cu" "F.Mask" "F.Paste")
			(net "M_M_DQS_DP<1>")
		)
		(pad "DE78" smd circle
			(at 30.382464 14.702028)
			(size 0.4318 0.4318)
			(layers "F.Cu" "F.Mask" "F.Paste")
			(net "GND")
		)
		(pad "DE80" smd circle
			(at 32.099504 14.702028)
			(size 0.4318 0.4318)
			(layers "F.Cu" "F.Mask" "F.Paste")
			(net "M_L_DQ<10>")
		)
		(pad "DE82" smd circle
			(at 33.816544 14.702028)
			(size 0.4318 0.4318)
			(layers "F.Cu" "F.Mask" "F.Paste")
			(net "M_L_DQ<15>")
		)
		(pad "DE84" smd circle
			(at 35.533584 14.702028)
			(size 0.4318 0.4318)
			(layers "F.Cu" "F.Mask" "F.Paste")
			(net "M_K_DQ<13>")
		)
		(pad "DF3" smd circle
			(at -35.533584 16.997172)
			(size 0.4318 0.4318)
			(layers "F.Cu" "F.Mask" "F.Paste")
			(net "TP_P3E_CPU1_PE1_MP_TXP<4>")
		)
		(pad "DF5" smd circle
			(at -33.816544 16.997172)
			(size 0.4318 0.4318)
			(layers "F.Cu" "F.Mask" "F.Paste")
			(net "GND")
		)
		(pad "DF7" smd circle
			(at -32.099504 16.997172)
			(size 0.4318 0.4318)
			(layers "F.Cu" "F.Mask" "F.Paste")
			(net "GND")
		)
		(pad "DF9" smd circle
			(at -30.382464 16.997172)
			(size 0.4318 0.4318)
			(layers "F.Cu" "F.Mask" "F.Paste")
			(net "TP_P3E_CPU1_PE1_MP_RXP<5>")
		)
		(pad "DF11" smd circle
			(at -28.665424 16.997172)
			(size 0.4318 0.4318)
			(layers "F.Cu" "F.Mask" "F.Paste")
			(net "P3E_CPU1_PE3_MP_RXP<11>")
		)
		(pad "DF13" smd circle
			(at -26.948384 16.997172)
			(size 0.4318 0.4318)
			(layers "F.Cu" "F.Mask" "F.Paste")
			(net "PVCCIO_CPU1")
		)
		(pad "DF15" smd circle
			(at -25.231598 16.997172)
			(size 0.4318 0.4318)
			(layers "F.Cu" "F.Mask" "F.Paste")
			(net "TP_CPU1_UPI2_RSVD_CW14")
		)
		(pad "DF17" smd circle
			(at -23.514558 16.997172)
			(size 0.4318 0.4318)
			(layers "F.Cu" "F.Mask" "F.Paste")
			(net "TP_CPU1_UPI2_RSVD_CK13")
		)
		(pad "DF19" smd circle
			(at -21.797518 16.997172)
			(size 0.4318 0.4318)
			(layers "F.Cu" "F.Mask" "F.Paste")
			(net "GND")
		)
		(pad "DF21" smd circle
			(at -20.080478 16.997172)
			(size 0.4318 0.4318)
			(layers "F.Cu" "F.Mask" "F.Paste")
			(net "PVCCIO_CPU1")
		)
		(pad "DF23" smd circle
			(at -18.363438 16.997172)
			(size 0.4318 0.4318)
			(layers "F.Cu" "F.Mask" "F.Paste")
			(net "GND")
		)
		(pad "DF25" smd circle
			(at -16.646398 16.997172)
			(size 0.4318 0.4318)
			(layers "F.Cu" "F.Mask" "F.Paste")
			(net "M_L_DQ<62>")
		)
		(pad "DF27" smd circle
			(at -14.929612 16.997172)
			(size 0.4318 0.4318)
			(layers "F.Cu" "F.Mask" "F.Paste")
			(net "M_L_DQ<56>")
		)
		(pad "DF29" smd circle
			(at -13.212572 16.997172)
			(size 0.4318 0.4318)
			(layers "F.Cu" "F.Mask" "F.Paste")
			(net "GND")
		)
		(pad "DF31" smd circle
			(at -11.495532 16.997172)
			(size 0.4318 0.4318)
			(layers "F.Cu" "F.Mask" "F.Paste")
			(net "M_M_DQ<46>")
		)
		(pad "DF33" smd circle
			(at -9.778492 16.997172)
			(size 0.4318 0.4318)
			(layers "F.Cu" "F.Mask" "F.Paste")
			(net "M_M_DQ<40>")
		)
		(pad "DF35" smd circle
			(at -8.061452 16.997172)
			(size 0.4318 0.4318)
			(layers "F.Cu" "F.Mask" "F.Paste")
			(net "GND")
		)
		(pad "DF37" smd circle
			(at -6.344412 16.997172)
			(size 0.4318 0.4318)
			(layers "F.Cu" "F.Mask" "F.Paste")
			(net "GND")
		)
		(pad "DF39" smd circle
			(at -4.627626 16.997172)
			(size 0.4318 0.4318)
			(layers "F.Cu" "F.Mask" "F.Paste")
			(net "GND")
		)
		(pad "DF41" smd circle
			(at -2.910586 16.997172)
			(size 0.4318 0.4318)
			(layers "F.Cu" "F.Mask" "F.Paste")
			(net "GND")
		)
		(pad "DF45" smd circle
			(at 2.052066 15.197074)
			(size 0.4318 0.4318)
			(layers "F.Cu" "F.Mask" "F.Paste")
			(net "M_M_C<2>")
		)
		(pad "DF47" smd circle
			(at 3.769106 15.197074)
			(size 0.4318 0.4318)
			(layers "F.Cu" "F.Mask" "F.Paste")
			(net "M_M_ODT<3>")
		)
		(pad "DF49" smd circle
			(at 5.485892 15.197074)
			(size 0.4318 0.4318)
			(layers "F.Cu" "F.Mask" "F.Paste")
			(net "M_M_CS_N<1>")
		)
		(pad "DF51" smd circle
			(at 7.202932 15.197074)
			(size 0.4318 0.4318)
			(layers "F.Cu" "F.Mask" "F.Paste")
			(net "M_M_CS_N<4>")
		)
		(pad "DF53" smd circle
			(at 8.919972 15.197074)
			(size 0.4318 0.4318)
			(layers "F.Cu" "F.Mask" "F.Paste")
			(net "M_M_MA<0>")
		)
		(pad "DF55" smd circle
			(at 10.637012 15.197074)
			(size 0.4318 0.4318)
			(layers "F.Cu" "F.Mask" "F.Paste")
			(net "M_M_CLK_DN<1>")
		)
		(pad "DF57" smd circle
			(at 12.354052 15.197074)
			(size 0.4318 0.4318)
			(layers "F.Cu" "F.Mask" "F.Paste")
			(net "M_M_CLK_DN<3>")
		)
		(pad "DF59" smd circle
			(at 14.071092 15.197074)
			(size 0.4318 0.4318)
			(layers "F.Cu" "F.Mask" "F.Paste")
			(net "M_M_MA<5>")
		)
		(pad "DF61" smd circle
			(at 15.787878 15.197074)
			(size 0.4318 0.4318)
			(layers "F.Cu" "F.Mask" "F.Paste")
			(net "M_M_BG<1>")
		)
		(pad "DF63" smd circle
			(at 17.504918 15.197074)
			(size 0.4318 0.4318)
			(layers "F.Cu" "F.Mask" "F.Paste")
			(net "M_M_CKE<3>")
		)
		(pad "DF65" smd circle
			(at 19.221958 15.197074)
			(size 0.4318 0.4318)
			(layers "F.Cu" "F.Mask" "F.Paste")
			(net "GND")
		)
		(pad "DF67" smd circle
			(at 20.938998 15.197074)
			(size 0.4318 0.4318)
			(layers "F.Cu" "F.Mask" "F.Paste")
			(net "M_K_DQS_DN<8>")
		)
		(pad "DF69" smd circle
			(at 22.656038 15.197074)
			(size 0.4318 0.4318)
			(layers "F.Cu" "F.Mask" "F.Paste")
			(net "GND")
		)
		(pad "DF71" smd circle
			(at 24.373078 15.197074)
			(size 0.4318 0.4318)
			(layers "F.Cu" "F.Mask" "F.Paste")
			(net "M_M_DQ<20>")
		)
		(pad "DF73" smd circle
			(at 26.090118 15.197074)
			(size 0.4318 0.4318)
			(layers "F.Cu" "F.Mask" "F.Paste")
			(net "GND")
		)
	)
)
